# S9S_MB_2U (Grand Teton) — schematic netlist excerpt (pin names and nets, part order shuffled) for the footprints in the layout excerpt that follows; sources: Cadence DE-HDL packaged netlist, KiCad conversion of 03242023_DA0F0TMBIJ0_F0T_Motherboard_J_brd_V01_OCP.brd

R1005  Q_RES  10K 1% EMPTY  pkg 0402LF  page 127 : A = PU_PIROM_CPU1_SM_WP ; B = GND
PC1278  Q_CAP  22UF 4V 20% X6S  pkg C0805  page 282 : A = PVNN_MAIN_CPU0 ; B = GND
PR501  Q_RES  8.25K 0.1% CHIP  pkg 0402LF  page 282 : A = PVNN_MAIN_CPU0_FB ; B = PVNN_MAIN_CPU0_FB_RC

(kicad_pcb
	(version 20260206)
	(generator "pcbnew")
	(generator_version "10.0")
	(general
		(thickness 1.6)
		(legacy_teardrops no)
	)
	(paper "A4")
	(title_block
		(title "03242023_DA0F0TMBIJ0_F0T_Motherboard_J_brd_V01_OCP.brd")
		(comment 1 "Grand Teton / footprints 4105-4107 of 6105")
	)
	(layers
		(0 "F.Cu" signal "TOP")
		(4 "In1.Cu" signal "GND")
		(6 "In2.Cu" signal "IN1")
		(8 "In3.Cu" signal "GND1")
		(10 "In4.Cu" signal "IN2")
		(12 "In5.Cu" signal "GND2")
		(14 "In6.Cu" signal "IN3")
		(16 "In7.Cu" signal "GND3")
		(18 "In8.Cu" signal "VCC")
		(20 "In9.Cu" signal "VCC1")
		(22 "In10.Cu" signal "GND4")
		(24 "In11.Cu" signal "IN4")
		(26 "In12.Cu" signal "GND5")
		(28 "In13.Cu" signal "IN5")
		(30 "In14.Cu" signal "GND6")
		(32 "In15.Cu" signal "IN6")
		(34 "In16.Cu" signal "GND7")
		(2 "B.Cu" signal "BOTTOM")
		(9 "F.Adhes" user "F.Adhesive")
		(11 "B.Adhes" user "B.Adhesive")
		(13 "F.Paste" user "Package Geometry/Pastemask Top")
		(15 "B.Paste" user "Package Geometry/Pastemask Bottom")
		(5 "F.SilkS" user "Ref Des/Silkscreen Top")
		(7 "B.SilkS" user "Ref Des/Silkscreen Bottom")
		(1 "F.Mask" user "Board Geometry/Soldermask Top")
		(3 "B.Mask" user "Board Geometry/Soldermask Bottom")
		(17 "Dwgs.User" user "User.Drawings")
		(19 "Cmts.User" user "User.Comments")
		(21 "Eco1.User" user "User.Eco1")
		(23 "Eco2.User" user "User.Eco2")
		(25 "Edge.Cuts" user "Board Geometry/Outline")
		(27 "Margin" user)
		(31 "F.CrtYd" user "Package Geometry/Place Bound Top")
		(29 "B.CrtYd" user "Package Geometry/Place Bound Bottom")
		(35 "F.Fab" user "Ref Des/Assembly Top")
		(33 "B.Fab" user "Ref Des/Assembly Bottom")
	)
	(footprint ""
		(layer "F.Cu")
		(at 432.41468 -175.69942)
		(property "Reference" "PR501"
			(at 0 0 0)
			(layer "F.SilkS")
			(hide yes)
			(effects
				(font
					(size 1.27 1.27)
				)
			)
		)
		(property "Value" ""
			(at 0 0 0)
			(layer "F.Fab")
			(effects
				(font
					(size 1.27 1.27)
				)
			)
		)
		(duplicate_pad_numbers_are_jumpers no)
		(fp_line
			(start -0.7874 -0.4064)
			(end 0.7874 -0.4064)
			(stroke
				(width 0.1524)
				(type default)
			)
			(layer "F.SilkS")
		)
		(fp_line
			(start -0.7874 0.4064)
			(end -0.7874 -0.4064)
			(stroke
				(width 0.1524)
				(type default)
			)
			(layer "F.SilkS")
		)
		(fp_line
			(start 0.7874 -0.4064)
			(end 0.7874 0.4064)
			(stroke
				(width 0.1524)
				(type default)
			)
			(layer "F.SilkS")
		)
		(fp_line
			(start 0.7874 0.4064)
			(end -0.7874 0.4064)
			(stroke
				(width 0.1524)
				(type default)
			)
			(layer "F.SilkS")
		)
		(fp_line
			(start -0.67945 -0.305054)
			(end -0.12065 -0.305054)
			(stroke
				(width 0.1)
				(type default)
			)
			(layer "F.Fab")
		)
		(fp_line
			(start -0.67945 0.3048)
			(end -0.67945 -0.305054)
			(stroke
				(width 0.1)
				(type default)
			)
			(layer "F.Fab")
		)
		(fp_line
			(start -0.12065 -0.305054)
			(end -0.12065 -0.2794)
			(stroke
				(width 0.1)
				(type default)
			)
			(layer "F.Fab")
		)
		(fp_line
			(start -0.12065 -0.2794)
			(end 0.12065 -0.2794)
			(stroke
				(width 0.1)
				(type default)
			)
			(layer "F.Fab")
		)
		(fp_line
			(start -0.12065 0.2794)
			(end -0.12065 0.3048)
			(stroke
				(width 0.1)
				(type default)
			)
			(layer "F.Fab")
		)
		(fp_line
			(start -0.12065 0.3048)
			(end -0.67945 0.3048)
			(stroke
				(width 0.1)
				(type default)
			)
			(layer "F.Fab")
		)
		(fp_line
			(start 0.120396 0.2794)
			(end -0.12065 0.2794)
			(stroke
				(width 0.1)
				(type default)
			)
			(layer "F.Fab")
		)
		(fp_line
			(start 0.120396 0.3048)
			(end 0.120396 0.2794)
			(stroke
				(width 0.1)
				(type default)
			)
			(layer "F.Fab")
		)
		(fp_line
			(start 0.12065 -0.3048)
			(end 0.67945 -0.3048)
			(stroke
				(width 0.1)
				(type default)
			)
			(layer "F.Fab")
		)
		(fp_line
			(start 0.12065 -0.2794)
			(end 0.12065 -0.3048)
			(stroke
				(width 0.1)
				(type default)
			)
			(layer "F.Fab")
		)
		(fp_line
			(start 0.67945 -0.3048)
			(end 0.67945 0.3048)
			(stroke
				(width 0.1)
				(type default)
			)
			(layer "F.Fab")
		)
		(fp_line
			(start 0.67945 0.3048)
			(end 0.120396 0.3048)
			(stroke
				(width 0.1)
				(type default)
			)
			(layer "F.Fab")
		)
		(pad "1" smd circle
			(at -0.40005 0)
			(size 0 0)
			(layers "F.Cu" "F.Mask" "F.Paste")
			(net "PVNN_MAIN_CPU0_FB")
		)
		(pad "2" smd circle
			(at 0.40005 0)
			(size 0 0)
			(layers "F.Cu" "F.Mask" "F.Paste")
			(net "PVNN_MAIN_CPU0_FB_RC")
		)
	)
	(footprint ""
		(layer "F.Cu")
		(at 193.93408 -357.139748)
		(property "Reference" "R1005"
			(at 0 0 0)
			(layer "F.SilkS")
			(hide yes)
			(effects
				(font
					(size 1.27 1.27)
				)
			)
		)
		(property "Value" ""
			(at 0 0 0)
			(layer "F.Fab")
			(effects
				(font
					(size 1.27 1.27)
				)
			)
		)
		(duplicate_pad_numbers_are_jumpers no)
		(fp_line
			(start -0.7874 -0.4064)
			(end 0.7874 -0.4064)
			(stroke
				(width 0.1524)
				(type default)
			)
			(layer "F.SilkS")
		)
		(fp_line
			(start -0.7874 0.4064)
			(end -0.7874 -0.4064)
			(stroke
				(width 0.1524)
				(type default)
			)
			(layer "F.SilkS")
		)
		(fp_line
			(start 0.7874 -0.4064)
			(end 0.7874 0.4064)
			(stroke
				(width 0.1524)
				(type default)
			)
			(layer "F.SilkS")
		)
		(fp_line
			(start 0.7874 0.4064)
			(end -0.7874 0.4064)
			(stroke
				(width 0.1524)
				(type default)
			)
			(layer "F.SilkS")
		)
		(fp_line
			(start -0.67945 -0.305054)
			(end -0.12065 -0.305054)
			(stroke
				(width 0.1)
				(type default)
			)
			(layer "F.Fab")
		)
		(fp_line
			(start -0.67945 0.3048)
			(end -0.67945 -0.305054)
			(stroke
				(width 0.1)
				(type default)
			)
			(layer "F.Fab")
		)
		(fp_line
			(start -0.12065 -0.305054)
			(end -0.12065 -0.2794)
			(stroke
				(width 0.1)
				(type default)
			)
			(layer "F.Fab")
		)
		(fp_line
			(start -0.12065 -0.2794)
			(end 0.12065 -0.2794)
			(stroke
				(width 0.1)
				(type default)
			)
			(layer "F.Fab")
		)
		(fp_line
			(start -0.12065 0.2794)
			(end -0.12065 0.3048)
			(stroke
				(width 0.1)
				(type default)
			)
			(layer "F.Fab")
		)
		(fp_line
			(start -0.12065 0.3048)
			(end -0.67945 0.3048)
			(stroke
				(width 0.1)
				(type default)
			)
			(layer "F.Fab")
		)
		(fp_line
			(start 0.120396 0.2794)
			(end -0.12065 0.2794)
			(stroke
				(width 0.1)
				(type default)
			)
			(layer "F.Fab")
		)
		(fp_line
			(start 0.120396 0.3048)
			(end 0.120396 0.2794)
			(stroke
				(width 0.1)
				(type default)
			)
			(layer "F.Fab")
		)
		(fp_line
			(start 0.12065 -0.3048)
			(end 0.67945 -0.3048)
			(stroke
				(width 0.1)
				(type default)
			)
			(layer "F.Fab")
		)
		(fp_line
			(start 0.12065 -0.2794)
			(end 0.12065 -0.3048)
			(stroke
				(width 0.1)
				(type default)
			)
			(layer "F.Fab")
		)
		(fp_line
			(start 0.67945 -0.3048)
			(end 0.67945 0.3048)
			(stroke
				(width 0.1)
				(type default)
			)
			(layer "F.Fab")
		)
		(fp_line
			(start 0.67945 0.3048)
			(end 0.120396 0.3048)
			(stroke
				(width 0.1)
				(type default)
			)
			(layer "F.Fab")
		)
		(pad "1" smd circle
			(at -0.40005 0)
			(size 0 0)
			(layers "F.Cu" "F.Mask" "F.Paste")
			(net "PU_PIROM_CPU1_SM_WP")
		)
		(pad "2" smd circle
			(at 0.40005 0)
			(size 0 0)
			(layers "F.Cu" "F.Mask" "F.Paste")
			(net "GND")
		)
	)
	(footprint ""
		(layer "F.Cu")
		(at 446.73393 -181.983888)
		(property "Reference" "PC1278"
			(at 0 0 0)
			(layer "F.SilkS")
			(hide yes)
			(effects
				(font
					(size 1.27 1.27)
				)
			)
		)
		(property "Value" ""
			(at 0 0 0)
			(layer "F.Fab")
			(effects
				(font
					(size 1.27 1.27)
				)
			)
		)
		(duplicate_pad_numbers_are_jumpers no)
		(fp_line
			(start -1.524 -0.762)
			(end 1.524 -0.762)
			(stroke
				(width 0.1524)
				(type default)
			)
			(layer "F.SilkS")
		)
		(fp_line
			(start -1.524 0.762)
			(end -1.524 -0.762)
			(stroke
				(width 0.1524)
				(type default)
			)
			(layer "F.SilkS")
		)
		(fp_line
			(start 1.524 -0.762)
			(end 1.524 0.762)
			(stroke
				(width 0.1524)
				(type default)
			)
			(layer "F.SilkS")
		)
		(fp_line
			(start 1.524 0.762)
			(end -1.524 0.762)
			(stroke
				(width 0.1524)
				(type default)
			)
			(layer "F.SilkS")
		)
		(fp_line
			(start -1.1049 -0.724916)
			(end -1.1049 0.724916)
			(stroke
				(width 0.1)
				(type default)
			)
			(layer "F.Fab")
		)
		(fp_line
			(start -1.1049 0.724916)
			(end 1.1049 0.724916)
			(stroke
				(width 0.1)
				(type default)
			)
			(layer "F.Fab")
		)
		(fp_line
			(start 1.1049 -0.724916)
			(end -1.1049 -0.724916)
			(stroke
				(width 0.1)
				(type default)
			)
			(layer "F.Fab")
		)
		(fp_line
			(start 1.1049 0.724916)
			(end 1.1049 -0.724916)
			(stroke
				(width 0.1)
				(type default)
			)
			(layer "F.Fab")
		)
		(pad "1" smd rect
			(at -0.889 0 180)
			(size 1.016 1.27)
			(layers "F.Cu" "F.Mask" "F.Paste")
			(net "PVNN_MAIN_CPU0")
		)
		(pad "2" smd rect
			(at 0.889 0 180)
			(size 1.016 1.27)
			(layers "F.Cu" "F.Mask" "F.Paste")
			(net "GND")
		)
	)
)
